FILE_TYPE = MACRO_DRAWING;
SET COLOR_WIRE YELLOW;
SET COLOR_PROP MONO;
SET COLOR_DOT WHITE;
SET COLOR_ARC YELLOW;
SET COLOR_BODY GREEN;
SET COLOR_NOTE MONO;
SET PROP_DISPLAY VALUE;
SET PAGE_NUMBER P12;
FORCEADD INTEL_CORP_BPAGE..1
(13000 175);
FORCEPROP 1 LAST CUSTOM_TXT_CDS <CURRENT_DESIGN_SHEET> OF <TOTAL_DESIGN_SHEETS>
J 0
(12500 200);
PAINT GREEN (12500 200);
FORCEPROP 2 LAST CUSTOM_TXT_CDS <XR_PAGE_TITLE>
J 0
(5110 5425);
DISPLAY 0.638298 (5110 5425);
PAINT PINK (5110 5425);
DISPLAY INVISIBLE (5110 5425);
FORCEPROP 2 LAST CUSTOM_TXT_CDS <CON_LAST_MODIFIED>
J 0
(11075 525);
PAINT GREEN (11075 525);
FORCEPROP 2 LAST CUSTOM_TXT_CDS <CON_PAGE_NUM> OF <CON_TOTAL_PAGES>
J 0
(12500 200);
PAINT GREEN (12500 200);
FORCEPROP 1 LAST SCH_ADDRESS1 2200 Mission College Blvd.
J 0
(9025 300);
DISPLAY 0.617021 (9025 300);
PAINT GREEN (9025 300);
FORCEPROP 1 LAST SCH_ADDRESS3 Santa Clara, CA 95052-8119
J 0
(9025 200);
DISPLAY 0.617021 (9025 200);
PAINT GREEN (9025 200);
FORCEPROP 1 LAST SCH_ADDRESS2 P.O. BOX 58119
J 0
(9025 250);
DISPLAY 0.617021 (9025 250);
PAINT GREEN (9025 250);
FORCEPROP 1 LAST SCH_TITLE ADR BLOCK DIAGRAM
J 0
(5050 225);
DISPLAY 1.212766 (5050 225);
PAINT ORANGE (5050 225);
FORCEPROP 1 LAST SCH_NUMBER H4694802
J 0
(11700 325);
DISPLAY 1.212766 (11700 325);
PAINT YELLOW (11700 325);
FORCEPROP 1 LAST SCH_DEPT BESD
J 1
(8550 275);
DISPLAY 1.212766 (8550 275);
PAINT YELLOW (8550 275);
FORCEPROP 1 LAST SCH_REV 2.420
J 0
(12750 325);
DISPLAY 0.978723 (12750 325);
PAINT YELLOW (12750 325);
FORCEPROP 2 LAST PAGE_BORDER TRUE
J 0
(5110 5425);
DISPLAY 0.851064 (5110 5425);
PAINT PINK (5110 5425);
DISPLAY INVISIBLE (5110 5425);
FORCEPROP 2 LAST CDS_LIB mstr_symbols
J 0
(13000 175);
PAINT MONO (13000 175);
DISPLAY INVISIBLE (13000 175);
FORCEPROP 1 LAST COMMENT_BODY TRUE
J 0
(13012 187);
DISPLAY 0.446809 (13012 187);
PAINT GREEN (13012 187);
DISPLAY INVISIBLE (13012 187);
FORCEPROP 1 LAST CDS_CON_LAST_MODIFIED Tue Dec 01 11:47:58 2015
J 0
(11575 500);
PAINT ORANGE (11575 500);
DISPLAY INVISIBLE (11575 500);
FORCEPROP 2 LAST CDS_XR_PAGE_TITLE CR-12 : @BASEBOARD_FAB2_LIB.BASEBOARD_FAB2(SCH_1):PAGE12
J 0
(5110 5425);
DISPLAY 0.638298 (5110 5425);
PAINT PINK (5110 5425);
DISPLAY INVISIBLE (5110 5425);
FORCENOTE
$CDS_IMAGE|12_ADR NVDIMM BLOCK DIAGRAM.jpg|4722|4555
(8625 2875) 0;
DISPLAY CENTER (8625 2875);
PAINT MONO (8625 2875);
QUIT
